(kicad_pcb
	(version 20241229)
	(generator "pcbnew")
	(generator_version "9.0")
	(general
		(thickness 1.6642)
		(legacy_teardrops no)
	)
	(paper "A3")
	(title_block
		(title "PolarFire SoM")
		(date "2025-07-22")
		(rev "1.1.4")
		(company "Antmicro Ltd")
		(comment 1 "www.antmicro.com")
		(comment 9 "footprints 157-160 of 470")
	)
	(layers
		(0 "F.Cu" mixed)
		(4 "In1.Cu" power)
		(6 "In2.Cu" signal)
		(8 "In3.Cu" power)
		(10 "In4.Cu" signal)
		(12 "In5.Cu" power)
		(14 "In6.Cu" power)
		(16 "In7.Cu" signal)
		(18 "In8.Cu" power)
		(20 "In9.Cu" signal)
		(22 "In10.Cu" power)
		(24 "In11.Cu" signal)
		(26 "In12.Cu" signal)
		(2 "B.Cu" mixed)
		(9 "F.Adhes" user "F.Adhesive")
		(11 "B.Adhes" user "B.Adhesive")
		(13 "F.Paste" user)
		(15 "B.Paste" user)
		(5 "F.SilkS" user "F.Silkscreen")
		(7 "B.SilkS" user "B.Silkscreen")
		(1 "F.Mask" user)
		(3 "B.Mask" user)
		(17 "Dwgs.User" user "User.Drawings")
		(19 "Cmts.User" user "User.Comments")
		(21 "Eco1.User" user "User.Eco1")
		(23 "Eco2.User" user "User.Eco2")
		(25 "Edge.Cuts" user)
		(27 "Margin" user)
		(31 "F.CrtYd" user "F.Courtyard")
		(29 "B.CrtYd" user "B.Courtyard")
		(35 "F.Fab" user)
		(33 "B.Fab" user)
	)
	(footprint "antmicro-footprints:SOT-523"
		(layer "B.Cu")
		(at 183.6 154.2)
		(property "Reference" "Q6"
			(at -4.35 1.05 90)
			(layer "B.SilkS")
			(effects
				(font
					(size 0.7 0.7)
					(thickness 0.15)
				)
				(justify right bottom mirror)
			)
		)
		(property "Value" "DMG1012T-7"
			(at 0.1 -1.824 0)
			(layer "B.Fab")
			(hide yes)
			(effects
				(font
					(size 0.7 0.7)
					(thickness 0.15)
				)
				(justify right bottom mirror)
			)
		)
		(property "Datasheet" "https://www.diodes.com/assets/Datasheets/ds31783.pdf"
			(at 0 0 0)
			(layer "F.Fab")
			(hide yes)
			(effects
				(font
					(size 1.27 1.27)
					(thickness 0.15)
				)
			)
		)
		(property "Description" "Power MOSFET, N Channel, 20 V, 630 mA, 0.3 ohm, SOT-523, Surface Mount"
			(at 0 0 0)
			(layer "F.Fab")
			(hide yes)
			(effects
				(font
					(size 1.27 1.27)
					(thickness 0.15)
				)
			)
		)
		(property "Author" "Antmicro"
			(at 0 0 0)
			(layer "B.Fab")
			(hide yes)
			(effects
				(font
					(size 1 1)
					(thickness 0.15)
				)
				(justify mirror)
			)
		)
		(property "License" "Apache-2.0"
			(at 0 0 0)
			(layer "B.Fab")
			(hide yes)
			(effects
				(font
					(size 1 1)
					(thickness 0.15)
				)
				(justify mirror)
			)
		)
		(property "MPN" "DMG1012T-7"
			(at 0 0 0)
			(layer "B.Fab")
			(hide yes)
			(effects
				(font
					(size 1 1)
					(thickness 0.15)
				)
				(justify mirror)
			)
		)
		(property "Manufacturer" "Diodes Incorporated"
			(at 0 0 0)
			(layer "B.Fab")
			(hide yes)
			(effects
				(font
					(size 1 1)
					(thickness 0.15)
				)
				(justify mirror)
			)
		)
		(property "Public" ""
			(at 0 0 0)
			(layer "B.Fab")
			(hide yes)
			(effects
				(font
					(size 1 1)
					(thickness 0.15)
				)
				(justify mirror)
			)
		)
		(sheetname "/Supply/")
		(sheetfile "supply.kicad_sch")
		(attr smd)
		(fp_line
			(start -0.927 0.051)
			(end -0.927 0.351)
			(stroke
				(width 0.15)
				(type solid)
			)
			(layer "B.SilkS")
		)
		(fp_line
			(start -0.927 0.351)
			(end -0.725 0.551)
			(stroke
				(width 0.15)
				(type solid)
			)
			(layer "B.SilkS")
		)
		(fp_line
			(start -0.725 0.551)
			(end -0.277 0.551)
			(stroke
				(width 0.15)
				(type solid)
			)
			(layer "B.SilkS")
		)
		(fp_line
			(start -0.277 0.551)
			(end -0.277 0.75)
			(stroke
				(width 0.15)
				(type solid)
			)
			(layer "B.SilkS")
		)
		(fp_circle
			(center -0.9652 -0.9652)
			(end -0.9152 -0.9652)
			(stroke
				(width 0.15)
				(type solid)
			)
			(fill yes)
			(layer "B.SilkS")
		)
		(fp_line
			(start -1.12 -1.15)
			(end 1.1 -1.15)
			(stroke
				(width 0.05)
				(type solid)
			)
			(layer "B.CrtYd")
		)
		(fp_line
			(start -1.12 1.16)
			(end -1.12 -1.15)
			(stroke
				(width 0.05)
				(type solid)
			)
			(layer "B.CrtYd")
		)
		(fp_line
			(start -1.12 1.16)
			(end 1.1 1.16)
			(stroke
				(width 0.05)
				(type solid)
			)
			(layer "B.CrtYd")
		)
		(fp_line
			(start 1.1 1.16)
			(end 1.1 -1.15)
			(stroke
				(width 0.05)
				(type solid)
			)
			(layer "B.CrtYd")
		)
		(fp_line
			(start -0.802 0.276)
			(end -0.802 -0.424)
			(stroke
				(width 0.15)
				(type solid)
			)
			(layer "B.Fab")
		)
		(fp_line
			(start -0.652 0.425)
			(end -0.802 0.276)
			(stroke
				(width 0.15)
				(type solid)
			)
			(layer "B.Fab")
		)
		(fp_line
			(start 0.8 -0.424)
			(end -0.802 -0.424)
			(stroke
				(width 0.15)
				(type solid)
			)
			(layer "B.Fab")
		)
		(fp_line
			(start 0.8 0.425)
			(end -0.652 0.425)
			(stroke
				(width 0.15)
				(type solid)
			)
			(layer "B.Fab")
		)
		(fp_line
			(start 0.8 0.425)
			(end 0.8 -0.424)
			(stroke
				(width 0.15)
				(type solid)
			)
			(layer "B.Fab")
		)
		(fp_circle
			(center -0.9652 -0.9652)
			(end -0.9144 -0.9652)
			(stroke
				(width 0.15)
				(type solid)
			)
			(fill no)
			(layer "B.Fab")
		)
		(fp_text user "License: Apache-2.0"
			(at -1.12 -5.024 180)
			(layer "B.Fab")
			(effects
				(font
					(size 0.7 0.7)
					(thickness 0.15)
				)
				(justify left bottom mirror)
			)
		)
		(fp_text user "Author: Antmicro"
			(at -1.12 -6.224 180)
			(layer "B.Fab")
			(effects
				(font
					(size 0.7 0.7)
					(thickness 0.15)
				)
				(justify left bottom mirror)
			)
		)
		(fp_text user "${REFERENCE}"
			(at -1.12 -3.824 180)
			(layer "B.Fab")
			(effects
				(font
					(size 0.7 0.7)
					(thickness 0.15)
				)
				(justify left bottom mirror)
			)
		)
		(pad "1" smd rect
			(at -0.5 -0.65)
			(size 0.4 0.51)
			(layers "B.Cu" "B.Mask" "B.Paste")
			(net 656 "/Supply/PG")
			(pinfunction "G")
			(pintype "input")
		)
		(pad "2" smd rect
			(at 0.498 -0.65)
			(size 0.4 0.51)
			(layers "B.Cu" "B.Mask" "B.Paste")
			(net 417 "GND")
			(pinfunction "S")
			(pintype "passive")
		)
		(pad "3" smd rect
			(at 0 0.652)
			(size 0.4 0.51)
			(layers "B.Cu" "B.Mask" "B.Paste")
			(net 230 "~{PG}")
			(pinfunction "D")
			(pintype "passive")
		)
	)
	(footprint "antmicro-footprints:R_0402_1005Metric"
		(layer "B.Cu")
		(at 181.3 152.05 90)
		(descr "Resistor SMD 0402")
		(tags "resistor SMD 0402")
		(property "Reference" "R64"
			(at 2.95 0.3 270)
			(layer "B.SilkS")
			(effects
				(font
					(size 0.7 0.7)
					(thickness 0.15)
				)
				(justify left bottom mirror)
			)
		)
		(property "Value" "R_93k1_0402"
			(at -1.011843 -1.772047 270)
			(layer "B.Fab")
			(hide yes)
			(effects
				(font
					(size 0.7 0.7)
					(thickness 0.15)
				)
				(justify left bottom mirror)
			)
		)
		(property "Datasheet" "https://www.bourns.com/docs/product-datasheets/cr.pdf"
			(at 0 0 90)
			(layer "F.Fab")
			(hide yes)
			(effects
				(font
					(size 1.27 1.27)
					(thickness 0.15)
				)
			)
		)
		(property "Description" "SMD Chip Resistor"
			(at 0 0 90)
			(layer "F.Fab")
			(hide yes)
			(effects
				(font
					(size 1.27 1.27)
					(thickness 0.15)
				)
			)
		)
		(property "Author" "Antmicro"
			(at 333.35 -29.25 0)
			(layer "B.Fab")
			(hide yes)
			(effects
				(font
					(size 1 1)
					(thickness 0.15)
				)
				(justify mirror)
			)
		)
		(property "License" "Apache-2.0"
			(at 333.35 -29.25 0)
			(layer "B.Fab")
			(hide yes)
			(effects
				(font
					(size 1 1)
					(thickness 0.15)
				)
				(justify mirror)
			)
		)
		(property "MPN" "CR0402-FX-9312GLF"
			(at 333.35 -29.25 0)
			(layer "B.Fab")
			(hide yes)
			(effects
				(font
					(size 1 1)
					(thickness 0.15)
				)
				(justify mirror)
			)
		)
		(property "Manufacturer" "Bourns"
			(at 333.35 -29.25 0)
			(layer "B.Fab")
			(hide yes)
			(effects
				(font
					(size 1 1)
					(thickness 0.15)
				)
				(justify mirror)
			)
		)
		(property "Public" ""
			(at 333.35 -29.25 0)
			(layer "B.Fab")
			(hide yes)
			(effects
				(font
					(size 1 1)
					(thickness 0.15)
				)
				(justify mirror)
			)
		)
		(property "Tolerance" "1%"
			(at 333.35 -29.25 0)
			(layer "B.Fab")
			(hide yes)
			(effects
				(font
					(size 1 1)
					(thickness 0.15)
				)
				(justify mirror)
			)
		)
		(property "Val" "93k1"
			(at 333.35 -29.25 0)
			(layer "B.Fab")
			(hide yes)
			(effects
				(font
					(size 1 1)
					(thickness 0.15)
				)
				(justify mirror)
			)
		)
		(sheetname "/Supply/")
		(sheetfile "supply.kicad_sch")
		(attr smd)
		(fp_rect
			(start -0.925 0.47)
			(end 0.925 -0.47)
			(stroke
				(width 0.05)
				(type default)
			)
			(fill no)
			(layer "B.CrtYd")
		)
		(fp_rect
			(start -0.5 0.25)
			(end 0.5 -0.25)
			(stroke
				(width 0.15)
				(type solid)
			)
			(fill no)
			(layer "B.Fab")
		)
		(fp_text user "Author: Antmicro"
			(at -0.95 -4.169 270)
			(layer "B.Fab")
			(effects
				(font
					(size 0.7 0.7)
					(thickness 0.15)
				)
				(justify left bottom mirror)
			)
		)
		(fp_text user "License: Apache-2.0"
			(at -0.95 -5.169 270)
			(layer "B.Fab")
			(effects
				(font
					(size 0.7 0.7)
					(thickness 0.15)
				)
				(justify left bottom mirror)
			)
		)
		(fp_text user "${REFERENCE}"
			(at -0.95 -3.168 270)
			(layer "B.Fab")
			(effects
				(font
					(size 0.7 0.7)
					(thickness 0.15)
				)
				(justify left bottom mirror)
			)
		)
		(pad "1" smd roundrect
			(at -0.48 0 90)
			(size 0.59 0.64)
			(layers "B.Cu" "B.Mask" "B.Paste")
			(roundrect_rratio 0.25)
			(net 14 "Net-(C111-Pad1)")
			(pintype "passive")
		)
		(pad "2" smd roundrect
			(at 0.48 0 90)
			(size 0.59 0.64)
			(layers "B.Cu" "B.Mask" "B.Paste")
			(roundrect_rratio 0.25)
			(net 522 "/Supply/1V05_REG")
			(pintype "passive")
		)
	)
	(footprint "antmicro-footprints:C_0402_1005Metric"
		(layer "B.Cu")
		(at 208.12 143.58 180)
		(descr "Capacitor SMD 0402")
		(tags "capacitor SMD 0402")
		(property "Reference" "C201"
			(at 5.62 18.42 0)
			(layer "B.SilkS")
			(effects
				(font
					(size 0.7 0.7)
					(thickness 0.15)
				)
				(justify left bottom mirror)
			)
		)
		(property "Value" "C_10u_10V_0402"
			(at -1.022927 -2.155213 0)
			(layer "B.Fab")
			(hide yes)
			(effects
				(font
					(size 0.7 0.7)
					(thickness 0.15)
				)
				(justify left bottom mirror)
			)
		)
		(property "Datasheet" "https://www.murata.com/products/productdetail?partno=GRM155R61A106ME11%23"
			(at 0 0 180)
			(layer "F.Fab")
			(hide yes)
			(effects
				(font
					(size 1.27 1.27)
					(thickness 0.15)
				)
			)
		)
		(property "Description" "Multilayer Ceramic Capacitors MLCC - SMD/SMT 10 uF 10 VDC 20% 0402 X5R"
			(at 0 0 180)
			(layer "F.Fab")
			(hide yes)
			(effects
				(font
					(size 1.27 1.27)
					(thickness 0.15)
				)
			)
		)
		(property "Author" "Antmicro"
			(at 416.24 287.16 0)
			(layer "B.Fab")
			(hide yes)
			(effects
				(font
					(size 1 1)
					(thickness 0.15)
				)
				(justify mirror)
			)
		)
		(property "Dielectric" "X5R"
			(at 416.24 287.16 0)
			(layer "B.Fab")
			(hide yes)
			(effects
				(font
					(size 1 1)
					(thickness 0.15)
				)
				(justify mirror)
			)
		)
		(property "License" "Apache-2.0"
			(at 416.24 287.16 0)
			(layer "B.Fab")
			(hide yes)
			(effects
				(font
					(size 1 1)
					(thickness 0.15)
				)
				(justify mirror)
			)
		)
		(property "MPN" "GRM155R61A106ME11D"
			(at 416.24 287.16 0)
			(layer "B.Fab")
			(hide yes)
			(effects
				(font
					(size 1 1)
					(thickness 0.15)
				)
				(justify mirror)
			)
		)
		(property "Manufacturer" "Murata"
			(at 416.24 287.16 0)
			(layer "B.Fab")
			(hide yes)
			(effects
				(font
					(size 1 1)
					(thickness 0.15)
				)
				(justify mirror)
			)
		)
		(property "Public" ""
			(at 416.24 287.16 0)
			(layer "B.Fab")
			(hide yes)
			(effects
				(font
					(size 1 1)
					(thickness 0.15)
				)
				(justify mirror)
			)
		)
		(property "Val" "10u"
			(at 416.24 287.16 0)
			(layer "B.Fab")
			(hide yes)
			(effects
				(font
					(size 1 1)
					(thickness 0.15)
				)
				(justify mirror)
			)
		)
		(property "Voltage" "10V"
			(at 416.24 287.16 0)
			(layer "B.Fab")
			(hide yes)
			(effects
				(font
					(size 1 1)
					(thickness 0.15)
				)
				(justify mirror)
			)
		)
		(sheetname "/MIPI CrossLink/")
		(sheetfile "crosslink.kicad_sch")
		(attr smd)
		(fp_rect
			(start -0.925 0.47)
			(end 0.925 -0.47)
			(stroke
				(width 0.05)
				(type default)
			)
			(fill no)
			(layer "B.CrtYd")
		)
		(fp_line
			(start 0.504 0.25)
			(end 0.504 -0.248)
			(stroke
				(width 0.15)
				(type solid)
			)
			(layer "B.Fab")
		)
		(fp_line
			(start 0.504 -0.248)
			(end -0.494 -0.248)
			(stroke
				(width 0.15)
				(type solid)
			)
			(layer "B.Fab")
		)
		(fp_line
			(start -0.494 0.25)
			(end 0.504 0.25)
			(stroke
				(width 0.15)
				(type solid)
			)
			(layer "B.Fab")
		)
		(fp_line
			(start -0.494 -0.248)
			(end -0.494 0.25)
			(stroke
				(width 0.15)
				(type solid)
			)
			(layer "B.Fab")
		)
		(fp_text user "${REFERENCE}"
			(at -0.939 -4.599 0)
			(layer "B.Fab")
			(effects
				(font
					(size 0.7 0.7)
					(thickness 0.15)
				)
				(justify left bottom mirror)
			)
		)
		(fp_text user "Author: Antmicro"
			(at -0.939 -3.399 0)
			(layer "B.Fab")
			(effects
				(font
					(size 0.7 0.7)
					(thickness 0.15)
				)
				(justify left bottom mirror)
			)
		)
		(fp_text user "License: Apache-2.0"
			(at -0.939 -5.799 0)
			(layer "B.Fab")
			(effects
				(font
					(size 0.7 0.7)
					(thickness 0.15)
				)
				(justify left bottom mirror)
			)
		)
		(pad "1" smd roundrect
			(at -0.48 0 180)
			(size 0.59 0.64)
			(layers "B.Cu" "B.Mask" "B.Paste")
			(roundrect_rratio 0.25)
			(net 417 "GND")
			(pintype "passive")
		)
		(pad "2" smd roundrect
			(at 0.48 0 180)
			(size 0.59 0.64)
			(layers "B.Cu" "B.Mask" "B.Paste")
			(roundrect_rratio 0.25)
			(net 191 "/MIPI CrossLink/CL_VCCIO2")
			(pintype "passive")
		)
	)
	(footprint "antmicro-footprints:C_0402_1005Metric"
		(layer "B.Cu")
		(at 203.21 125.7)
		(descr "Capacitor SMD 0402")
		(tags "capacitor SMD 0402")
		(property "Reference" "C23"
			(at 0.91 0.895 0)
			(layer "B.SilkS")
			(effects
				(font
					(size 0.7 0.7)
					(thickness 0.15)
				)
				(justify right bottom mirror)
			)
		)
		(property "Value" "C_10u_0402"
			(at -1.022927 -2.155213 0)
			(layer "B.Fab")
			(hide yes)
			(effects
				(font
					(size 0.7 0.7)
					(thickness 0.15)
				)
				(justify right bottom mirror)
			)
		)
		(property "Datasheet" "https://www.yageo.com/en/Chart/Download/pdf/CC0402MRX5R5BB106"
			(at 0 0 0)
			(layer "F.Fab")
			(hide yes)
			(effects
				(font
					(size 1.27 1.27)
					(thickness 0.15)
				)
			)
		)
		(property "Description" "SMD Multilayer Ceramic Capacitor, 10 µF, 6.3 V, 0402 [1005 Metric], ± 20%, X5R, CC Series"
			(at 0 0 0)
			(layer "F.Fab")
			(hide yes)
			(effects
				(font
					(size 1.27 1.27)
					(thickness 0.15)
				)
			)
		)
		(property "Author" "Antmicro"
			(at 0 0 0)
			(layer "B.Fab")
			(hide yes)
			(effects
				(font
					(size 1 1)
					(thickness 0.15)
				)
				(justify mirror)
			)
		)
		(property "Dielectric" ""
			(at 0 0 0)
			(layer "B.Fab")
			(hide yes)
			(effects
				(font
					(size 1 1)
					(thickness 0.15)
				)
				(justify mirror)
			)
		)
		(property "License" "Apache-2.0"
			(at 0 0 0)
			(layer "B.Fab")
			(hide yes)
			(effects
				(font
					(size 1 1)
					(thickness 0.15)
				)
				(justify mirror)
			)
		)
		(property "MPN" "CC0402MRX5R5BB106"
			(at 0 0 0)
			(layer "B.Fab")
			(hide yes)
			(effects
				(font
					(size 1 1)
					(thickness 0.15)
				)
				(justify mirror)
			)
		)
		(property "Manufacturer" "YAGEO"
			(at 0 0 0)
			(layer "B.Fab")
			(hide yes)
			(effects
				(font
					(size 1 1)
					(thickness 0.15)
				)
				(justify mirror)
			)
		)
		(property "Public" ""
			(at 0 0 0)
			(layer "B.Fab")
			(hide yes)
			(effects
				(font
					(size 1 1)
					(thickness 0.15)
				)
				(justify mirror)
			)
		)
		(property "Val" "10u"
			(at 0 0 0)
			(layer "B.Fab")
			(hide yes)
			(effects
				(font
					(size 1 1)
					(thickness 0.15)
				)
				(justify mirror)
			)
		)
		(property "Voltage" ""
			(at 0 0 0)
			(layer "B.Fab")
			(hide yes)
			(effects
				(font
					(size 1 1)
					(thickness 0.15)
				)
				(justify mirror)
			)
		)
		(sheetname "/FPGA Supply/")
		(sheetfile "fpga-supply.kicad_sch")
		(attr smd)
		(fp_rect
			(start -0.925 0.47)
			(end 0.925 -0.47)
			(stroke
				(width 0.05)
				(type default)
			)
			(fill no)
			(layer "B.CrtYd")
		)
		(fp_line
			(start -0.494 -0.248)
			(end -0.494 0.25)
			(stroke
				(width 0.15)
				(type solid)
			)
			(layer "B.Fab")
		)
		(fp_line
			(start -0.494 0.25)
			(end 0.504 0.25)
			(stroke
				(width 0.15)
				(type solid)
			)
			(layer "B.Fab")
		)
		(fp_line
			(start 0.504 -0.248)
			(end -0.494 -0.248)
			(stroke
				(width 0.15)
				(type solid)
			)
			(layer "B.Fab")
		)
		(fp_line
			(start 0.504 0.25)
			(end 0.504 -0.248)
			(stroke
				(width 0.15)
				(type solid)
			)
			(layer "B.Fab")
		)
		(fp_text user "License: Apache-2.0"
			(at -0.939 -5.799 180)
			(layer "B.Fab")
			(effects
				(font
					(size 0.7 0.7)
					(thickness 0.15)
				)
				(justify left bottom mirror)
			)
		)
		(fp_text user "Author: Antmicro"
			(at -0.939 -3.399 180)
			(layer "B.Fab")
			(effects
				(font
					(size 0.7 0.7)
					(thickness 0.15)
				)
				(justify left bottom mirror)
			)
		)
		(fp_text user "${REFERENCE}"
			(at -0.939 -4.599 180)
			(layer "B.Fab")
			(effects
				(font
					(size 0.7 0.7)
					(thickness 0.15)
				)
				(justify left bottom mirror)
			)
		)
		(pad "1" smd roundrect
			(at -0.48 0)
			(size 0.59 0.64)
			(layers "B.Cu" "B.Mask" "B.Paste")
			(roundrect_rratio 0.25)
			(net 417 "GND")
			(pintype "passive")
		)
		(pad "2" smd roundrect
			(at 0.48 0)
			(size 0.59 0.64)
			(layers "B.Cu" "B.Mask" "B.Paste")
			(roundrect_rratio 0.25)
			(net 649 "VDD")
			(pintype "passive")
		)
	)
)
